# T6G (Grand Teton) — schematic netlist excerpt (pin names and nets, part order shuffled) for the footprints in the layout excerpt that follows; sources: Cadence DE-HDL packaged netlist, KiCad conversion of 04192023_DAF0TMB3IC0_F0TG_MB_C_brd_V02_OCP.brd

R2705  Q_RES  0 5% EMPTY  pkg 0402LF  page 248 : A = SMB_BMC_SWB_R_SCL ; B = SMB_BMC_SWB_BUF_R_SCL
C2422  Q_CAP  22UF 4V 20% X6S  pkg C0402  page 74 : A = PVDDCR_SOC_P1 ; B = GND

(kicad_pcb
	(version 20260206)
	(generator "pcbnew")
	(generator_version "10.0")
	(general
		(thickness 1.6)
		(legacy_teardrops no)
	)
	(paper "A4")
	(title_block
		(title "04192023_DAF0TMB3IC0_F0TG_MB_C_brd_V02_OCP.brd")
		(comment 1 "Grand Teton / footprints 856-857 of 8354")
	)
	(layers
		(0 "F.Cu" signal "TOP")
		(4 "In1.Cu" signal "GND")
		(6 "In2.Cu" signal "IN1")
		(8 "In3.Cu" signal "GND1")
		(10 "In4.Cu" signal "IN2")
		(12 "In5.Cu" signal "GND2")
		(14 "In6.Cu" signal "IN3")
		(16 "In7.Cu" signal "GND3")
		(18 "In8.Cu" signal "VCC")
		(20 "In9.Cu" signal "VCC1")
		(22 "In10.Cu" signal "GND4")
		(24 "In11.Cu" signal "IN4")
		(26 "In12.Cu" signal "GND5")
		(28 "In13.Cu" signal "IN5")
		(30 "In14.Cu" signal "GND6")
		(32 "In15.Cu" signal "IN6")
		(34 "In16.Cu" signal "GND7")
		(2 "B.Cu" signal "BOTTOM")
		(9 "F.Adhes" user "F.Adhesive")
		(11 "B.Adhes" user "B.Adhesive")
		(13 "F.Paste" user "Package Geometry/Pastemask Top")
		(15 "B.Paste" user "Package Geometry/Pastemask Bottom")
		(5 "F.SilkS" user "Ref Des/Silkscreen Top")
		(7 "B.SilkS" user "Ref Des/Silkscreen Bottom")
		(1 "F.Mask" user "Board Geometry/Soldermask Top")
		(3 "B.Mask" user "Board Geometry/Soldermask Bottom")
		(17 "Dwgs.User" user "User.Drawings")
		(19 "Cmts.User" user "User.Comments")
		(21 "Eco1.User" user "User.Eco1")
		(23 "Eco2.User" user "User.Eco2")
		(25 "Edge.Cuts" user "Board Geometry/Outline")
		(27 "Margin" user)
		(31 "F.CrtYd" user "Package Geometry/Place Bound Top")
		(29 "B.CrtYd" user "Package Geometry/Place Bound Bottom")
		(35 "F.Fab" user "Ref Des/Assembly Top")
		(33 "B.Fab" user "Ref Des/Assembly Bottom")
	)
	(footprint ""
		(layer "F.Cu")
		(at 117.895624 -257.455416 180)
		(property "Reference" "C2422"
			(at 0 0 180)
			(layer "F.SilkS")
			(hide yes)
			(effects
				(font
					(size 1.27 1.27)
				)
			)
		)
		(property "Value" ""
			(at 0 0 180)
			(layer "F.Fab")
			(effects
				(font
					(size 1.27 1.27)
				)
			)
		)
		(duplicate_pad_numbers_are_jumpers no)
		(fp_line
			(start 0.7874 0.4064)
			(end -0.7874 0.4064)
			(stroke
				(width 0.1524)
				(type default)
			)
			(layer "F.SilkS")
		)
		(fp_line
			(start 0.7874 -0.4064)
			(end 0.7874 0.4064)
			(stroke
				(width 0.1524)
				(type default)
			)
			(layer "F.SilkS")
		)
		(fp_line
			(start -0.7874 0.4064)
			(end -0.7874 -0.4064)
			(stroke
				(width 0.1524)
				(type default)
			)
			(layer "F.SilkS")
		)
		(fp_line
			(start -0.7874 -0.4064)
			(end 0.7874 -0.4064)
			(stroke
				(width 0.1524)
				(type default)
			)
			(layer "F.SilkS")
		)
		(fp_line
			(start 0.67945 0.3048)
			(end 0.120396 0.3048)
			(stroke
				(width 0.1)
				(type default)
			)
			(layer "F.Fab")
		)
		(fp_line
			(start 0.67945 -0.3048)
			(end 0.67945 0.3048)
			(stroke
				(width 0.1)
				(type default)
			)
			(layer "F.Fab")
		)
		(fp_line
			(start 0.12065 -0.2794)
			(end 0.12065 -0.3048)
			(stroke
				(width 0.1)
				(type default)
			)
			(layer "F.Fab")
		)
		(fp_line
			(start 0.12065 -0.3048)
			(end 0.67945 -0.3048)
			(stroke
				(width 0.1)
				(type default)
			)
			(layer "F.Fab")
		)
		(fp_line
			(start 0.120396 0.3048)
			(end 0.120396 0.2794)
			(stroke
				(width 0.1)
				(type default)
			)
			(layer "F.Fab")
		)
		(fp_line
			(start 0.120396 0.2794)
			(end -0.12065 0.2794)
			(stroke
				(width 0.1)
				(type default)
			)
			(layer "F.Fab")
		)
		(fp_line
			(start -0.12065 0.3048)
			(end -0.67945 0.3048)
			(stroke
				(width 0.1)
				(type default)
			)
			(layer "F.Fab")
		)
		(fp_line
			(start -0.12065 0.2794)
			(end -0.12065 0.3048)
			(stroke
				(width 0.1)
				(type default)
			)
			(layer "F.Fab")
		)
		(fp_line
			(start -0.12065 -0.2794)
			(end 0.12065 -0.2794)
			(stroke
				(width 0.1)
				(type default)
			)
			(layer "F.Fab")
		)
		(fp_line
			(start -0.12065 -0.305054)
			(end -0.12065 -0.2794)
			(stroke
				(width 0.1)
				(type default)
			)
			(layer "F.Fab")
		)
		(fp_line
			(start -0.67945 0.3048)
			(end -0.67945 -0.305054)
			(stroke
				(width 0.1)
				(type default)
			)
			(layer "F.Fab")
		)
		(fp_line
			(start -0.67945 -0.305054)
			(end -0.12065 -0.305054)
			(stroke
				(width 0.1)
				(type default)
			)
			(layer "F.Fab")
		)
		(pad "1" smd circle
			(at -0.40005 0 180)
			(size 0 0)
			(layers "F.Cu" "F.Mask" "F.Paste")
			(net "PVDDCR_SOC_P1")
		)
		(pad "2" smd circle
			(at 0.40005 0 180)
			(size 0 0)
			(layers "F.Cu" "F.Mask" "F.Paste")
			(net "GND")
		)
	)
	(footprint ""
		(layer "F.Cu")
		(at 165.8112 -429.9712 90)
		(property "Reference" "R2705"
			(at 0 0 90)
			(layer "F.SilkS")
			(hide yes)
			(effects
				(font
					(size 1.27 1.27)
				)
			)
		)
		(property "Value" ""
			(at 0 0 90)
			(layer "F.Fab")
			(effects
				(font
					(size 1.27 1.27)
				)
			)
		)
		(duplicate_pad_numbers_are_jumpers no)
		(fp_line
			(start 0.7874 -0.4064)
			(end 0.7874 0.4064)
			(stroke
				(width 0.1524)
				(type default)
			)
			(layer "F.SilkS")
		)
		(fp_line
			(start -0.7874 -0.4064)
			(end 0.7874 -0.4064)
			(stroke
				(width 0.1524)
				(type default)
			)
			(layer "F.SilkS")
		)
		(fp_line
			(start 0.7874 0.4064)
			(end -0.7874 0.4064)
			(stroke
				(width 0.1524)
				(type default)
			)
			(layer "F.SilkS")
		)
		(fp_line
			(start -0.7874 0.4064)
			(end -0.7874 -0.4064)
			(stroke
				(width 0.1524)
				(type default)
			)
			(layer "F.SilkS")
		)
		(fp_line
			(start -0.12065 -0.305054)
			(end -0.12065 -0.2794)
			(stroke
				(width 0.1)
				(type default)
			)
			(layer "F.Fab")
		)
		(fp_line
			(start -0.67945 -0.305054)
			(end -0.12065 -0.305054)
			(stroke
				(width 0.1)
				(type default)
			)
			(layer "F.Fab")
		)
		(fp_line
			(start 0.67945 -0.3048)
			(end 0.67945 0.3048)
			(stroke
				(width 0.1)
				(type default)
			)
			(layer "F.Fab")
		)
		(fp_line
			(start 0.12065 -0.3048)
			(end 0.67945 -0.3048)
			(stroke
				(width 0.1)
				(type default)
			)
			(layer "F.Fab")
		)
		(fp_line
			(start 0.12065 -0.2794)
			(end 0.12065 -0.3048)
			(stroke
				(width 0.1)
				(type default)
			)
			(layer "F.Fab")
		)
		(fp_line
			(start -0.12065 -0.2794)
			(end 0.12065 -0.2794)
			(stroke
				(width 0.1)
				(type default)
			)
			(layer "F.Fab")
		)
		(fp_line
			(start 0.120396 0.2794)
			(end -0.12065 0.2794)
			(stroke
				(width 0.1)
				(type default)
			)
			(layer "F.Fab")
		)
		(fp_line
			(start -0.12065 0.2794)
			(end -0.12065 0.3048)
			(stroke
				(width 0.1)
				(type default)
			)
			(layer "F.Fab")
		)
		(fp_line
			(start 0.67945 0.3048)
			(end 0.120396 0.3048)
			(stroke
				(width 0.1)
				(type default)
			)
			(layer "F.Fab")
		)
		(fp_line
			(start 0.120396 0.3048)
			(end 0.120396 0.2794)
			(stroke
				(width 0.1)
				(type default)
			)
			(layer "F.Fab")
		)
		(fp_line
			(start -0.12065 0.3048)
			(end -0.67945 0.3048)
			(stroke
				(width 0.1)
				(type default)
			)
			(layer "F.Fab")
		)
		(fp_line
			(start -0.67945 0.3048)
			(end -0.67945 -0.305054)
			(stroke
				(width 0.1)
				(type default)
			)
			(layer "F.Fab")
		)
		(pad "1" smd circle
			(at -0.40005 0 90)
			(size 0 0)
			(layers "F.Cu" "F.Mask" "F.Paste")
			(net "SMB_BMC_SWB_R_SCL")
		)
		(pad "2" smd circle
			(at 0.40005 0 90)
			(size 0 0)
			(layers "F.Cu" "F.Mask" "F.Paste")
			(net "SMB_BMC_SWB_BUF_R_SCL")
		)
	)
)
